# T6G (Grand Teton) — schematic netlist excerpt (pin names and nets, part order shuffled) for the footprints in the layout excerpt that follows; sources: Cadence DE-HDL packaged netlist, KiCad conversion of 04192023_DAF0TMB3IC0_F0TG_MB_C_brd_V02_OCP.brd

U107  PI3CSW12ZUAEX  IC  pkg UQFN10_0-5_2X1-5  page 159
  \1d+\  = I3C_0_SPD_DDRAF_CPU1_SCL
  \1d-\  = I3C_0_SPD_DDRAF_CPU1_SDA
  \2d+\  = I3C_SCM_2_R_SCL
  \2d-\  = I3C_SCM_2_R_SDA
  GND  = GND
  \oe#\  = FM_I3C_CPU1_MUX0_OE_N
  \d-\  = I3C_SPD_DDRAF_CPU1_LVC1_SDA
  \d+\  = I3C_SPD_DDRAF_CPU1_LVC1_SCL
  S  = FM_I3C_CPU1_MUX0_SEL
  VDD  = P3V3_AUX

C741  Q_CAP_DIFFBUS  DIFF BUS_0.22UF 6.3V 20% X6S  pkg C0201  page 66 : \1\ = P5E_CPU1_P1_TX_C_DP<0> ; \2\ = P5E_CPU1_P1_TX_DP<0>
R960  Q_RES  0 5% EMPTY  pkg 0402LF  page 279 : A = P1V8_CPU0_RT_1D ; B = P1V8_CPU0_RT0_1A_1D

(kicad_pcb
	(version 20260206)
	(generator "pcbnew")
	(generator_version "10.0")
	(general
		(thickness 1.6)
		(legacy_teardrops no)
	)
	(paper "A4")
	(title_block
		(title "04192023_DAF0TMB3IC0_F0TG_MB_C_brd_V02_OCP.brd")
		(comment 1 "Grand Teton / footprints 747-749 of 8354")
	)
	(layers
		(0 "F.Cu" signal "TOP")
		(4 "In1.Cu" signal "GND")
		(6 "In2.Cu" signal "IN1")
		(8 "In3.Cu" signal "GND1")
		(10 "In4.Cu" signal "IN2")
		(12 "In5.Cu" signal "GND2")
		(14 "In6.Cu" signal "IN3")
		(16 "In7.Cu" signal "GND3")
		(18 "In8.Cu" signal "VCC")
		(20 "In9.Cu" signal "VCC1")
		(22 "In10.Cu" signal "GND4")
		(24 "In11.Cu" signal "IN4")
		(26 "In12.Cu" signal "GND5")
		(28 "In13.Cu" signal "IN5")
		(30 "In14.Cu" signal "GND6")
		(32 "In15.Cu" signal "IN6")
		(34 "In16.Cu" signal "GND7")
		(2 "B.Cu" signal "BOTTOM")
		(9 "F.Adhes" user "F.Adhesive")
		(11 "B.Adhes" user "B.Adhesive")
		(13 "F.Paste" user "Package Geometry/Pastemask Top")
		(15 "B.Paste" user "Package Geometry/Pastemask Bottom")
		(5 "F.SilkS" user "Ref Des/Silkscreen Top")
		(7 "B.SilkS" user "Ref Des/Silkscreen Bottom")
		(1 "F.Mask" user "Board Geometry/Soldermask Top")
		(3 "B.Mask" user "Board Geometry/Soldermask Bottom")
		(17 "Dwgs.User" user "User.Drawings")
		(19 "Cmts.User" user "User.Comments")
		(21 "Eco1.User" user "User.Eco1")
		(23 "Eco2.User" user "User.Eco2")
		(25 "Edge.Cuts" user "Board Geometry/Outline")
		(27 "Margin" user)
		(31 "F.CrtYd" user "Package Geometry/Place Bound Top")
		(29 "B.CrtYd" user "Package Geometry/Place Bound Bottom")
		(35 "F.Fab" user "Ref Des/Assembly Top")
		(33 "B.Fab" user "Ref Des/Assembly Bottom")
	)
	(footprint ""
		(layer "F.Cu")
		(at 38.78707 -171.980606 180)
		(property "Reference" "U107"
			(at -2.3368 -2.662682 0)
			(unlocked yes)
			(layer "F.SilkS")
			(effects
				(font
					(size 0.7874 0.5842)
					(thickness 0.1524)
				)
			)
		)
		(property "Value" ""
			(at 0 0 180)
			(layer "F.Fab")
			(effects
				(font
					(size 1.27 1.27)
				)
			)
		)
		(duplicate_pad_numbers_are_jumpers no)
		(fp_line
			(start 1.03378 1.284478)
			(end -1.03378 1.284478)
			(stroke
				(width 0.1524)
				(type default)
			)
			(layer "F.SilkS")
		)
		(fp_line
			(start 1.03378 -1.284478)
			(end 1.03378 1.284478)
			(stroke
				(width 0.1524)
				(type default)
			)
			(layer "F.SilkS")
		)
		(fp_line
			(start -1.03378 1.284478)
			(end -1.03378 -1.284478)
			(stroke
				(width 0.1524)
				(type default)
			)
			(layer "F.SilkS")
		)
		(fp_line
			(start -1.03378 -1.284478)
			(end 1.03378 -1.284478)
			(stroke
				(width 0.1524)
				(type default)
			)
			(layer "F.SilkS")
		)
		(fp_poly
			(pts
				(xy -1.663192 -1.558798) (xy -1.327658 -0.971296) (xy -1.99898 -1.05537)
			)
			(stroke
				(width 0)
				(type default)
			)
			(fill yes)
			(layer "F.SilkS")
		)
		(fp_line
			(start 0.774954 1.02489)
			(end -0.774954 1.02489)
			(stroke
				(width 0.1)
				(type default)
			)
			(layer "F.Fab")
		)
		(fp_line
			(start 0.774954 -1.02489)
			(end 0.774954 1.02489)
			(stroke
				(width 0.1)
				(type default)
			)
			(layer "F.Fab")
		)
		(fp_line
			(start -0.774954 1.02489)
			(end -0.774954 -1.02489)
			(stroke
				(width 0.1)
				(type default)
			)
			(layer "F.Fab")
		)
		(fp_line
			(start -0.774954 -1.02489)
			(end 0.774954 -1.02489)
			(stroke
				(width 0.1)
				(type default)
			)
			(layer "F.Fab")
		)
		(fp_poly
			(pts
				(xy -1.201674 -0.750062) (xy -1.806702 -0.447548) (xy -1.806702 -1.052576)
			)
			(stroke
				(width 0)
				(type default)
			)
			(fill yes)
			(layer "F.Fab")
		)
		(pad "1" smd rect
			(at -0.64008 -0.750062 270)
			(size 0.3048 0.5334)
			(layers "F.Cu" "F.Mask" "F.Paste")
			(net "I3C_0_SPD_DDRAF_CPU1_SCL")
		)
		(pad "2" smd rect
			(at -0.64008 -0.249936 270)
			(size 0.254 0.5334)
			(layers "F.Cu" "F.Mask" "F.Paste")
			(net "I3C_0_SPD_DDRAF_CPU1_SDA")
		)
		(pad "3" smd rect
			(at -0.64008 0.249936 270)
			(size 0.254 0.5334)
			(layers "F.Cu" "F.Mask" "F.Paste")
			(net "I3C_SCM_2_R_SCL")
		)
		(pad "4" smd rect
			(at -0.64008 0.750062 270)
			(size 0.3048 0.5334)
			(layers "F.Cu" "F.Mask" "F.Paste")
			(net "I3C_SCM_2_R_SDA")
		)
		(pad "5" smd rect
			(at 0 0.839978 180)
			(size 0.3302 0.635)
			(layers "F.Cu" "F.Mask" "F.Paste")
			(net "GND")
		)
		(pad "6" smd rect
			(at 0.64008 0.750062 270)
			(size 0.3048 0.5334)
			(layers "F.Cu" "F.Mask" "F.Paste")
			(net "FM_I3C_CPU1_MUX0_OE_N")
		)
		(pad "7" smd rect
			(at 0.64008 0.249936 270)
			(size 0.254 0.5334)
			(layers "F.Cu" "F.Mask" "F.Paste")
			(net "I3C_SPD_DDRAF_CPU1_LVC1_SDA")
		)
		(pad "8" smd rect
			(at 0.64008 -0.249936 270)
			(size 0.254 0.5334)
			(layers "F.Cu" "F.Mask" "F.Paste")
			(net "I3C_SPD_DDRAF_CPU1_LVC1_SCL")
		)
		(pad "9" smd rect
			(at 0.64008 -0.750062 270)
			(size 0.3048 0.5334)
			(layers "F.Cu" "F.Mask" "F.Paste")
			(net "FM_I3C_CPU1_MUX0_SEL")
		)
		(pad "10" smd rect
			(at 0 -0.839978 180)
			(size 0.3302 0.635)
			(layers "F.Cu" "F.Mask" "F.Paste")
			(net "P3V3_AUX")
		)
	)
	(footprint ""
		(layer "F.Cu")
		(at 326.662288 -392.48588 180)
		(property "Reference" "R960"
			(at 0 0 180)
			(layer "F.SilkS")
			(hide yes)
			(effects
				(font
					(size 1.27 1.27)
				)
			)
		)
		(property "Value" ""
			(at 0 0 180)
			(layer "F.Fab")
			(effects
				(font
					(size 1.27 1.27)
				)
			)
		)
		(duplicate_pad_numbers_are_jumpers no)
		(fp_line
			(start 0.7874 0.4064)
			(end -0.7874 0.4064)
			(stroke
				(width 0.1524)
				(type default)
			)
			(layer "F.SilkS")
		)
		(fp_line
			(start 0.7874 -0.4064)
			(end 0.7874 0.4064)
			(stroke
				(width 0.1524)
				(type default)
			)
			(layer "F.SilkS")
		)
		(fp_line
			(start -0.7874 0.4064)
			(end -0.7874 -0.4064)
			(stroke
				(width 0.1524)
				(type default)
			)
			(layer "F.SilkS")
		)
		(fp_line
			(start -0.7874 -0.4064)
			(end 0.7874 -0.4064)
			(stroke
				(width 0.1524)
				(type default)
			)
			(layer "F.SilkS")
		)
		(fp_line
			(start 0.67945 0.3048)
			(end 0.120396 0.3048)
			(stroke
				(width 0.1)
				(type default)
			)
			(layer "F.Fab")
		)
		(fp_line
			(start 0.67945 -0.3048)
			(end 0.67945 0.3048)
			(stroke
				(width 0.1)
				(type default)
			)
			(layer "F.Fab")
		)
		(fp_line
			(start 0.12065 -0.2794)
			(end 0.12065 -0.3048)
			(stroke
				(width 0.1)
				(type default)
			)
			(layer "F.Fab")
		)
		(fp_line
			(start 0.12065 -0.3048)
			(end 0.67945 -0.3048)
			(stroke
				(width 0.1)
				(type default)
			)
			(layer "F.Fab")
		)
		(fp_line
			(start 0.120396 0.3048)
			(end 0.120396 0.2794)
			(stroke
				(width 0.1)
				(type default)
			)
			(layer "F.Fab")
		)
		(fp_line
			(start 0.120396 0.2794)
			(end -0.12065 0.2794)
			(stroke
				(width 0.1)
				(type default)
			)
			(layer "F.Fab")
		)
		(fp_line
			(start -0.12065 0.3048)
			(end -0.67945 0.3048)
			(stroke
				(width 0.1)
				(type default)
			)
			(layer "F.Fab")
		)
		(fp_line
			(start -0.12065 0.2794)
			(end -0.12065 0.3048)
			(stroke
				(width 0.1)
				(type default)
			)
			(layer "F.Fab")
		)
		(fp_line
			(start -0.12065 -0.2794)
			(end 0.12065 -0.2794)
			(stroke
				(width 0.1)
				(type default)
			)
			(layer "F.Fab")
		)
		(fp_line
			(start -0.12065 -0.305054)
			(end -0.12065 -0.2794)
			(stroke
				(width 0.1)
				(type default)
			)
			(layer "F.Fab")
		)
		(fp_line
			(start -0.67945 0.3048)
			(end -0.67945 -0.305054)
			(stroke
				(width 0.1)
				(type default)
			)
			(layer "F.Fab")
		)
		(fp_line
			(start -0.67945 -0.305054)
			(end -0.12065 -0.305054)
			(stroke
				(width 0.1)
				(type default)
			)
			(layer "F.Fab")
		)
		(pad "1" smd rect
			(at -0.40005 0)
			(size 0.4572 0.508)
			(layers "F.Cu" "F.Mask" "F.Paste")
			(net "P1V8_CPU0_RT_1D")
		)
		(pad "2" smd rect
			(at 0.40005 0)
			(size 0.4572 0.508)
			(layers "F.Cu" "F.Mask" "F.Paste")
			(net "P1V8_CPU0_RT0_1A_1D")
		)
	)
	(footprint ""
		(layer "F.Cu")
		(at 75.49515 -382.39446 180)
		(property "Reference" "C741"
			(at 0 0 180)
			(layer "F.SilkS")
			(hide yes)
			(effects
				(font
					(size 1.27 1.27)
				)
			)
		)
		(property "Value" ""
			(at 0 0 180)
			(layer "F.Fab")
			(effects
				(font
					(size 1.27 1.27)
				)
			)
		)
		(duplicate_pad_numbers_are_jumpers no)
		(fp_line
			(start 0.299974 0.150114)
			(end -0.299974 0.150114)
			(stroke
				(width 0.1)
				(type default)
			)
			(layer "F.Fab")
		)
		(fp_line
			(start 0.299974 -0.150114)
			(end 0.299974 0.150114)
			(stroke
				(width 0.1)
				(type default)
			)
			(layer "F.Fab")
		)
		(fp_line
			(start -0.299974 0.150114)
			(end -0.299974 -0.150114)
			(stroke
				(width 0.1)
				(type default)
			)
			(layer "F.Fab")
		)
		(fp_line
			(start -0.299974 -0.150114)
			(end 0.299974 -0.150114)
			(stroke
				(width 0.1)
				(type default)
			)
			(layer "F.Fab")
		)
		(pad "1" smd rect
			(at -0.2667 0 180)
			(size 0.3048 0.381)
			(layers "F.Cu" "F.Mask" "F.Paste")
			(net "P5E_CPU1_P1_TX_C_DP<0>")
		)
		(pad "2" smd rect
			(at 0.2667 0 180)
			(size 0.3048 0.381)
			(layers "F.Cu" "F.Mask" "F.Paste")
			(net "P5E_CPU1_P1_TX_DP<0>")
		)
	)
)
